# T6G (Grand Teton) — schematic netlist excerpt (pin names and nets, part order shuffled) for the footprints in the layout excerpt that follows; sources: Cadence DE-HDL packaged netlist, KiCad conversion of 04192023_DAF0TMB3IC0_F0TG_MB_C_brd_V02_OCP.brd

C2545  Q_CAP  22UF 4V 20% X6S  pkg C0402  page 70 : A = PVDDCR_SOC_P0 ; B = GND
R201  Q_RES  4.7K 5% EMPTY  pkg 0402LF  page 160 : A = P3V3_AUX ; B = PU_U2_EN

(kicad_pcb
	(version 20260206)
	(generator "pcbnew")
	(generator_version "10.0")
	(general
		(thickness 1.6)
		(legacy_teardrops no)
	)
	(paper "A4")
	(title_block
		(title "04192023_DAF0TMB3IC0_F0TG_MB_C_brd_V02_OCP.brd")
		(comment 1 "Grand Teton / footprints 6863-6864 of 8354")
	)
	(layers
		(0 "F.Cu" signal "TOP")
		(4 "In1.Cu" signal "GND")
		(6 "In2.Cu" signal "IN1")
		(8 "In3.Cu" signal "GND1")
		(10 "In4.Cu" signal "IN2")
		(12 "In5.Cu" signal "GND2")
		(14 "In6.Cu" signal "IN3")
		(16 "In7.Cu" signal "GND3")
		(18 "In8.Cu" signal "VCC")
		(20 "In9.Cu" signal "VCC1")
		(22 "In10.Cu" signal "GND4")
		(24 "In11.Cu" signal "IN4")
		(26 "In12.Cu" signal "GND5")
		(28 "In13.Cu" signal "IN5")
		(30 "In14.Cu" signal "GND6")
		(32 "In15.Cu" signal "IN6")
		(34 "In16.Cu" signal "GND7")
		(2 "B.Cu" signal "BOTTOM")
		(9 "F.Adhes" user "F.Adhesive")
		(11 "B.Adhes" user "B.Adhesive")
		(13 "F.Paste" user "Package Geometry/Pastemask Top")
		(15 "B.Paste" user "Package Geometry/Pastemask Bottom")
		(5 "F.SilkS" user "Ref Des/Silkscreen Top")
		(7 "B.SilkS" user "Ref Des/Silkscreen Bottom")
		(1 "F.Mask" user "Board Geometry/Soldermask Top")
		(3 "B.Mask" user "Board Geometry/Soldermask Bottom")
		(17 "Dwgs.User" user "User.Drawings")
		(19 "Cmts.User" user "User.Comments")
		(21 "Eco1.User" user "User.Eco1")
		(23 "Eco2.User" user "User.Eco2")
		(25 "Edge.Cuts" user "Board Geometry/Outline")
		(27 "Margin" user)
		(31 "F.CrtYd" user "Package Geometry/Place Bound Top")
		(29 "B.CrtYd" user "Package Geometry/Place Bound Bottom")
		(35 "F.Fab" user "Ref Des/Assembly Top")
		(33 "B.Fab" user "Ref Des/Assembly Bottom")
	)
	(footprint ""
		(layer "B.Cu")
		(at 373.329454 -252.54331)
		(property "Reference" "C2545"
			(at 0 0 0)
			(layer "B.SilkS")
			(hide yes)
			(effects
				(font
					(size 1.27 1.27)
				)
				(justify mirror)
			)
		)
		(property "Value" ""
			(at 0 0 0)
			(layer "B.Fab")
			(effects
				(font
					(size 1.27 1.27)
				)
				(justify mirror)
			)
		)
		(duplicate_pad_numbers_are_jumpers no)
		(fp_line
			(start -0.7874 -0.4064)
			(end -0.7874 0.4064)
			(stroke
				(width 0.1524)
				(type default)
			)
			(layer "B.SilkS")
		)
		(fp_line
			(start -0.7874 0.4064)
			(end 0.7874 0.4064)
			(stroke
				(width 0.1524)
				(type default)
			)
			(layer "B.SilkS")
		)
		(fp_line
			(start 0.7874 -0.4064)
			(end -0.7874 -0.4064)
			(stroke
				(width 0.1524)
				(type default)
			)
			(layer "B.SilkS")
		)
		(fp_line
			(start 0.7874 0.4064)
			(end 0.7874 -0.4064)
			(stroke
				(width 0.1524)
				(type default)
			)
			(layer "B.SilkS")
		)
		(fp_line
			(start -0.67945 -0.3048)
			(end -0.67945 0.3048)
			(stroke
				(width 0.1)
				(type default)
			)
			(layer "B.Fab")
		)
		(fp_line
			(start -0.67945 0.3048)
			(end -0.120396 0.3048)
			(stroke
				(width 0.1)
				(type default)
			)
			(layer "B.Fab")
		)
		(fp_line
			(start -0.12065 -0.3048)
			(end -0.67945 -0.3048)
			(stroke
				(width 0.1)
				(type default)
			)
			(layer "B.Fab")
		)
		(fp_line
			(start -0.12065 -0.2794)
			(end -0.12065 -0.3048)
			(stroke
				(width 0.1)
				(type default)
			)
			(layer "B.Fab")
		)
		(fp_line
			(start -0.120396 0.2794)
			(end 0.12065 0.2794)
			(stroke
				(width 0.1)
				(type default)
			)
			(layer "B.Fab")
		)
		(fp_line
			(start -0.120396 0.3048)
			(end -0.120396 0.2794)
			(stroke
				(width 0.1)
				(type default)
			)
			(layer "B.Fab")
		)
		(fp_line
			(start 0.12065 -0.305054)
			(end 0.12065 -0.2794)
			(stroke
				(width 0.1)
				(type default)
			)
			(layer "B.Fab")
		)
		(fp_line
			(start 0.12065 -0.2794)
			(end -0.12065 -0.2794)
			(stroke
				(width 0.1)
				(type default)
			)
			(layer "B.Fab")
		)
		(fp_line
			(start 0.12065 0.2794)
			(end 0.12065 0.3048)
			(stroke
				(width 0.1)
				(type default)
			)
			(layer "B.Fab")
		)
		(fp_line
			(start 0.12065 0.3048)
			(end 0.67945 0.3048)
			(stroke
				(width 0.1)
				(type default)
			)
			(layer "B.Fab")
		)
		(fp_line
			(start 0.67945 -0.305054)
			(end 0.12065 -0.305054)
			(stroke
				(width 0.1)
				(type default)
			)
			(layer "B.Fab")
		)
		(fp_line
			(start 0.67945 0.3048)
			(end 0.67945 -0.305054)
			(stroke
				(width 0.1)
				(type default)
			)
			(layer "B.Fab")
		)
		(pad "1" smd circle
			(at 0.40005 0 180)
			(size 0 0)
			(layers "B.Cu" "B.Mask" "B.Paste")
			(net "PVDDCR_SOC_P0")
		)
		(pad "2" smd circle
			(at -0.40005 0 180)
			(size 0 0)
			(layers "B.Cu" "B.Mask" "B.Paste")
			(net "GND")
		)
	)
	(footprint ""
		(layer "B.Cu")
		(at 229.576122 -228.143308 90)
		(property "Reference" "R201"
			(at 0 0 90)
			(layer "B.SilkS")
			(hide yes)
			(effects
				(font
					(size 1.27 1.27)
				)
				(justify mirror)
			)
		)
		(property "Value" ""
			(at 0 0 90)
			(layer "B.Fab")
			(effects
				(font
					(size 1.27 1.27)
				)
				(justify mirror)
			)
		)
		(duplicate_pad_numbers_are_jumpers no)
		(fp_line
			(start 0.7874 -0.4064)
			(end -0.7874 -0.4064)
			(stroke
				(width 0.1524)
				(type default)
			)
			(layer "B.SilkS")
		)
		(fp_line
			(start -0.7874 -0.4064)
			(end -0.7874 0.4064)
			(stroke
				(width 0.1524)
				(type default)
			)
			(layer "B.SilkS")
		)
		(fp_line
			(start 0.7874 0.4064)
			(end 0.7874 -0.4064)
			(stroke
				(width 0.1524)
				(type default)
			)
			(layer "B.SilkS")
		)
		(fp_line
			(start -0.7874 0.4064)
			(end 0.7874 0.4064)
			(stroke
				(width 0.1524)
				(type default)
			)
			(layer "B.SilkS")
		)
		(fp_line
			(start 0.67945 -0.305054)
			(end 0.12065 -0.305054)
			(stroke
				(width 0.1)
				(type default)
			)
			(layer "B.Fab")
		)
		(fp_line
			(start 0.12065 -0.305054)
			(end 0.12065 -0.2794)
			(stroke
				(width 0.1)
				(type default)
			)
			(layer "B.Fab")
		)
		(fp_line
			(start -0.12065 -0.3048)
			(end -0.67945 -0.3048)
			(stroke
				(width 0.1)
				(type default)
			)
			(layer "B.Fab")
		)
		(fp_line
			(start -0.67945 -0.3048)
			(end -0.67945 0.3048)
			(stroke
				(width 0.1)
				(type default)
			)
			(layer "B.Fab")
		)
		(fp_line
			(start 0.12065 -0.2794)
			(end -0.12065 -0.2794)
			(stroke
				(width 0.1)
				(type default)
			)
			(layer "B.Fab")
		)
		(fp_line
			(start -0.12065 -0.2794)
			(end -0.12065 -0.3048)
			(stroke
				(width 0.1)
				(type default)
			)
			(layer "B.Fab")
		)
		(fp_line
			(start 0.12065 0.2794)
			(end 0.12065 0.3048)
			(stroke
				(width 0.1)
				(type default)
			)
			(layer "B.Fab")
		)
		(fp_line
			(start -0.120396 0.2794)
			(end 0.12065 0.2794)
			(stroke
				(width 0.1)
				(type default)
			)
			(layer "B.Fab")
		)
		(fp_line
			(start 0.67945 0.3048)
			(end 0.67945 -0.305054)
			(stroke
				(width 0.1)
				(type default)
			)
			(layer "B.Fab")
		)
		(fp_line
			(start 0.12065 0.3048)
			(end 0.67945 0.3048)
			(stroke
				(width 0.1)
				(type default)
			)
			(layer "B.Fab")
		)
		(fp_line
			(start -0.120396 0.3048)
			(end -0.120396 0.2794)
			(stroke
				(width 0.1)
				(type default)
			)
			(layer "B.Fab")
		)
		(fp_line
			(start -0.67945 0.3048)
			(end -0.120396 0.3048)
			(stroke
				(width 0.1)
				(type default)
			)
			(layer "B.Fab")
		)
		(pad "1" smd circle
			(at 0.40005 0 270)
			(size 0 0)
			(layers "B.Cu" "B.Mask" "B.Paste")
			(net "P3V3_AUX")
		)
		(pad "2" smd circle
			(at -0.40005 0 270)
			(size 0 0)
			(layers "B.Cu" "B.Mask" "B.Paste")
			(net "PU_U2_EN")
		)
	)
)
